(kicad_pcb
	(version 20260206)
	(generator "pcbnew")
	(generator_version "10.0")
	(general
		(thickness 1.6)
		(legacy_teardrops no)
	)
	(paper "A4")
	(title_block
		(title "Wiwynn_Tioga_Pass_MB.brd")
		(comment 1 "Tioga Pass / footprints 3175-3181 of 4770")
	)
	(layers
		(0 "F.Cu" signal "TOP")
		(4 "In1.Cu" signal "L2GND")
		(6 "In2.Cu" signal "L3")
		(8 "In3.Cu" signal "L4GND")
		(10 "In4.Cu" signal "L5")
		(12 "In5.Cu" signal "L6GND")
		(14 "In6.Cu" signal "L7VCC")
		(16 "In7.Cu" signal "L8VCC")
		(18 "In8.Cu" signal "L9GND")
		(20 "In9.Cu" signal "L10")
		(22 "In10.Cu" signal "L11GND")
		(24 "In11.Cu" signal "L12")
		(26 "In12.Cu" signal "L13GND")
		(2 "B.Cu" signal "BOTTOM")
		(9 "F.Adhes" user "F.Adhesive")
		(11 "B.Adhes" user "B.Adhesive")
		(13 "F.Paste" user "Package Geometry/Pastemask Top")
		(15 "B.Paste" user "Package Geometry/Pastemask Bottom")
		(5 "F.SilkS" user "Ref Des/Silkscreen Top")
		(7 "B.SilkS" user "Ref Des/Silkscreen Bottom")
		(1 "F.Mask" user "Board Geometry/Soldermask Top")
		(3 "B.Mask" user "Board Geometry/Soldermask Bottom")
		(17 "Dwgs.User" user "User.Drawings")
		(19 "Cmts.User" user "User.Comments")
		(21 "Eco1.User" user "User.Eco1")
		(23 "Eco2.User" user "User.Eco2")
		(25 "Edge.Cuts" user "Board Geometry/Outline")
		(27 "Margin" user)
		(31 "F.CrtYd" user "Package Geometry/Place Bound Top")
		(29 "B.CrtYd" user "Package Geometry/Place Bound Bottom")
		(35 "F.Fab" user "Ref Des/Assembly Top")
		(33 "B.Fab" user "Ref Des/Assembly Bottom")
	)
	(footprint ""
		(layer "B.Cu")
		(at 341.728806 -61.257434)
		(property "Reference" "C2U9"
			(at 0 0 0)
			(layer "B.SilkS")
			(hide yes)
			(effects
				(font
					(size 1.27 1.27)
				)
				(justify mirror)
			)
		)
		(property "Value" ""
			(at 0 0 0)
			(layer "B.Fab")
			(effects
				(font
					(size 1.27 1.27)
				)
				(justify mirror)
			)
		)
		(duplicate_pad_numbers_are_jumpers no)
		(fp_poly
			(pts
				(xy -0.3048 -0.1016) (xy -0.3048 0.9906) (xy 0.3048 0.9906) (xy 0.3048 -0.1016)
			)
			(stroke
				(width 0)
				(type default)
			)
			(fill no)
			(layer "B.CrtYd")
		)
		(fp_line
			(start -0.3048 -0.1016)
			(end 0.3048 -0.1016)
			(stroke
				(width 0.1)
				(type default)
			)
			(layer "B.Fab")
		)
		(fp_line
			(start -0.3048 0.9906)
			(end -0.3048 -0.1016)
			(stroke
				(width 0.1)
				(type default)
			)
			(layer "B.Fab")
		)
		(fp_line
			(start 0.3048 -0.1016)
			(end 0.3048 0.9906)
			(stroke
				(width 0.1)
				(type default)
			)
			(layer "B.Fab")
		)
		(fp_line
			(start 0.3048 0.9906)
			(end -0.3048 0.9906)
			(stroke
				(width 0.1)
				(type default)
			)
			(layer "B.Fab")
		)
		(pad "1" smd rect
			(at 0 0 180)
			(size 0.508 0.508)
			(layers "B.Cu" "B.Mask" "B.Paste")
			(net "P3E_CPU0_PE1_PCH_RXP<3>")
		)
		(pad "2" smd rect
			(at 0 0.889 180)
			(size 0.508 0.508)
			(layers "B.Cu" "B.Mask" "B.Paste")
			(net "P3E_CPU0_PE1_SS_RXP<3>")
		)
		(zone
			(layer "B.Cu")
			(hatch none 0.5)
			(connect_pads
				(clearance 0)
			)
			(min_thickness 0.25)
			(keepout
				(tracks allowed)
				(vias not_allowed)
				(pads allowed)
				(copperpour not_allowed)
				(footprints allowed)
			)
			(placement
				(enabled no)
				(sheetname "")
			)
			(fill
				(thermal_gap 0.5)
				(thermal_bridge_width 0.5)
				(island_removal_mode 0)
			)
			(polygon
				(pts
					(xy 341.982806 -61.003434) (xy 341.474806 -61.003434) (xy 341.474806 -60.622434) (xy 341.982806 -60.622434)
				)
			)
		)
		(zone
			(layer "B.Cu")
			(hatch none 0.5)
			(connect_pads
				(clearance 0)
			)
			(min_thickness 0.25)
			(keepout
				(tracks not_allowed)
				(vias allowed)
				(pads allowed)
				(copperpour not_allowed)
				(footprints allowed)
			)
			(placement
				(enabled no)
				(sheetname "")
			)
			(fill
				(thermal_gap 0.5)
				(thermal_bridge_width 0.5)
				(island_removal_mode 0)
			)
			(polygon
				(pts
					(xy 341.982806 -60.622434) (xy 341.474806 -60.622434) (xy 341.474806 -61.003434) (xy 341.982806 -61.003434)
				)
			)
		)
	)
	(footprint ""
		(layer "B.Cu")
		(at 351.416874 -22.949916 90)
		(property "Reference" "C3T14"
			(at -1.47828 0.78994 180)
			(unlocked yes)
			(layer "B.SilkS")
			(effects
				(font
					(size 0.4064 0.254)
					(thickness 0.1524)
				)
				(justify mirror)
			)
		)
		(property "Value" ""
			(at 0 0 90)
			(layer "B.Fab")
			(effects
				(font
					(size 1.27 1.27)
				)
				(justify mirror)
			)
		)
		(duplicate_pad_numbers_are_jumpers no)
		(fp_poly
			(pts
				(xy 0.7239 -0.2159) (xy -0.7239 -0.2159) (xy -0.7239 1.9939) (xy 0.7239 1.9939)
			)
			(stroke
				(width 0)
				(type default)
			)
			(fill no)
			(layer "B.CrtYd")
		)
		(fp_line
			(start 0.7239 -0.2159)
			(end 0.7239 1.9939)
			(stroke
				(width 0.1)
				(type default)
			)
			(layer "B.Fab")
		)
		(fp_line
			(start -0.7239 -0.2159)
			(end 0.7239 -0.2159)
			(stroke
				(width 0.1)
				(type default)
			)
			(layer "B.Fab")
		)
		(fp_line
			(start 0.7239 1.9939)
			(end -0.7239 1.9939)
			(stroke
				(width 0.1)
				(type default)
			)
			(layer "B.Fab")
		)
		(fp_line
			(start -0.7239 1.9939)
			(end -0.7239 -0.2159)
			(stroke
				(width 0.1)
				(type default)
			)
			(layer "B.Fab")
		)
		(pad "1" smd rect
			(at 0 0 270)
			(size 1.27 1.016)
			(layers "B.Cu" "B.Mask" "B.Paste")
			(net "VR_FET_SW_P12V_STBY_PVPP_ABC")
		)
		(pad "2" smd rect
			(at 0 1.778 270)
			(size 1.27 1.016)
			(layers "B.Cu" "B.Mask" "B.Paste")
			(net "GND")
		)
		(zone
			(layer "B.Cu")
			(hatch none 0.5)
			(connect_pads
				(clearance 0)
			)
			(min_thickness 0.25)
			(keepout
				(tracks not_allowed)
				(vias allowed)
				(pads allowed)
				(copperpour not_allowed)
				(footprints allowed)
			)
			(placement
				(enabled no)
				(sheetname "")
			)
			(fill
				(thermal_gap 0.5)
				(thermal_bridge_width 0.5)
				(island_removal_mode 0)
			)
			(polygon
				(pts
					(xy 351.924874 -23.584916) (xy 351.924874 -22.314916) (xy 352.686874 -22.314916) (xy 352.686874 -23.584916)
				)
			)
		)
	)
	(footprint ""
		(layer "B.Cu")
		(at 447.079878 -152.842722)
		(property "Reference" "C25W96"
			(at 0.8382 -0.67818 0)
			(unlocked yes)
			(layer "B.SilkS")
			(effects
				(font
					(size 0.4064 0.254)
					(thickness 0.1524)
				)
				(justify left mirror)
			)
		)
		(property "Value" ""
			(at 0 0 0)
			(layer "B.Fab")
			(effects
				(font
					(size 1.27 1.27)
				)
				(justify mirror)
			)
		)
		(duplicate_pad_numbers_are_jumpers no)
		(fp_poly
			(pts
				(xy -0.3048 -0.1016) (xy -0.3048 0.9906) (xy 0.3048 0.9906) (xy 0.3048 -0.1016)
			)
			(stroke
				(width 0)
				(type default)
			)
			(fill no)
			(layer "B.CrtYd")
		)
		(fp_line
			(start -0.3048 -0.1016)
			(end 0.3048 -0.1016)
			(stroke
				(width 0.1)
				(type default)
			)
			(layer "B.Fab")
		)
		(fp_line
			(start -0.3048 0.9906)
			(end -0.3048 -0.1016)
			(stroke
				(width 0.1)
				(type default)
			)
			(layer "B.Fab")
		)
		(fp_line
			(start 0.3048 -0.1016)
			(end 0.3048 0.9906)
			(stroke
				(width 0.1)
				(type default)
			)
			(layer "B.Fab")
		)
		(fp_line
			(start 0.3048 0.9906)
			(end -0.3048 0.9906)
			(stroke
				(width 0.1)
				(type default)
			)
			(layer "B.Fab")
		)
		(pad "1" smd rect
			(at 0 0 180)
			(size 0.508 0.508)
			(layers "B.Cu" "B.Mask" "B.Paste")
			(net "P3V3_STBY")
		)
		(pad "2" smd rect
			(at 0 0.889 180)
			(size 0.508 0.508)
			(layers "B.Cu" "B.Mask" "B.Paste")
			(net "GND")
		)
		(zone
			(layer "B.Cu")
			(hatch none 0.5)
			(connect_pads
				(clearance 0)
			)
			(min_thickness 0.25)
			(keepout
				(tracks allowed)
				(vias not_allowed)
				(pads allowed)
				(copperpour not_allowed)
				(footprints allowed)
			)
			(placement
				(enabled no)
				(sheetname "")
			)
			(fill
				(thermal_gap 0.5)
				(thermal_bridge_width 0.5)
				(island_removal_mode 0)
			)
			(polygon
				(pts
					(xy 447.333878 -152.588722) (xy 446.825878 -152.588722) (xy 446.825878 -152.207722) (xy 447.333878 -152.207722)
				)
			)
		)
		(zone
			(layer "B.Cu")
			(hatch none 0.5)
			(connect_pads
				(clearance 0)
			)
			(min_thickness 0.25)
			(keepout
				(tracks not_allowed)
				(vias allowed)
				(pads allowed)
				(copperpour not_allowed)
				(footprints allowed)
			)
			(placement
				(enabled no)
				(sheetname "")
			)
			(fill
				(thermal_gap 0.5)
				(thermal_bridge_width 0.5)
				(island_removal_mode 0)
			)
			(polygon
				(pts
					(xy 447.333878 -152.207722) (xy 446.825878 -152.207722) (xy 446.825878 -152.588722) (xy 447.333878 -152.588722)
				)
			)
		)
	)
	(footprint ""
		(layer "B.Cu")
		(at 470.027 -60.96 -90)
		(property "Reference" "R1R18"
			(at 0 0 90)
			(layer "B.SilkS")
			(hide yes)
			(effects
				(font
					(size 1.27 1.27)
				)
				(justify mirror)
			)
		)
		(property "Value" ""
			(at 0 0 90)
			(layer "B.Fab")
			(effects
				(font
					(size 1.27 1.27)
				)
				(justify mirror)
			)
		)
		(duplicate_pad_numbers_are_jumpers no)
		(fp_poly
			(pts
				(xy 0.2794 -0.1016) (xy -0.2794 -0.1016) (xy -0.2794 0.9906) (xy 0.2794 0.9906)
			)
			(stroke
				(width 0)
				(type default)
			)
			(fill no)
			(layer "B.CrtYd")
		)
		(fp_line
			(start -0.2794 0.9906)
			(end -0.2794 -0.1016)
			(stroke
				(width 0.1)
				(type default)
			)
			(layer "B.Fab")
		)
		(fp_line
			(start 0.2794 0.9906)
			(end -0.2794 0.9906)
			(stroke
				(width 0.1)
				(type default)
			)
			(layer "B.Fab")
		)
		(fp_line
			(start -0.2794 -0.1016)
			(end 0.2794 -0.1016)
			(stroke
				(width 0.1)
				(type default)
			)
			(layer "B.Fab")
		)
		(fp_line
			(start 0.2794 -0.1016)
			(end 0.2794 0.9906)
			(stroke
				(width 0.1)
				(type default)
			)
			(layer "B.Fab")
		)
		(pad "1" smd rect
			(at 0 0 90)
			(size 0.508 0.508)
			(layers "B.Cu" "B.Mask" "B.Paste")
			(net "P3V3_STBY")
		)
		(pad "2" smd rect
			(at 0 0.889 90)
			(size 0.508 0.508)
			(layers "B.Cu" "B.Mask" "B.Paste")
			(net "SMB_PCH_MEZZ_LOM0_SCL")
		)
		(zone
			(layer "B.Cu")
			(hatch none 0.5)
			(connect_pads
				(clearance 0)
			)
			(min_thickness 0.25)
			(keepout
				(tracks not_allowed)
				(vias allowed)
				(pads allowed)
				(copperpour not_allowed)
				(footprints allowed)
			)
			(placement
				(enabled no)
				(sheetname "")
			)
			(fill
				(thermal_gap 0.5)
				(thermal_bridge_width 0.5)
				(island_removal_mode 0)
			)
			(polygon
				(pts
					(xy 469.392 -60.706) (xy 469.392 -61.214) (xy 469.773 -61.214) (xy 469.773 -60.706)
				)
			)
		)
		(zone
			(layer "B.Cu")
			(hatch none 0.5)
			(connect_pads
				(clearance 0)
			)
			(min_thickness 0.25)
			(keepout
				(tracks allowed)
				(vias not_allowed)
				(pads allowed)
				(copperpour not_allowed)
				(footprints allowed)
			)
			(placement
				(enabled no)
				(sheetname "")
			)
			(fill
				(thermal_gap 0.5)
				(thermal_bridge_width 0.5)
				(island_removal_mode 0)
			)
			(polygon
				(pts
					(xy 469.773 -60.706) (xy 469.773 -61.214) (xy 469.392 -61.214) (xy 469.392 -60.706)
				)
			)
		)
	)
	(footprint ""
		(layer "B.Cu")
		(at 329.2094 -27.6733 180)
		(property "Reference" "C4T3"
			(at -3.12293 2.9083 270)
			(unlocked yes)
			(layer "B.SilkS")
			(effects
				(font
					(size 0.7874 0.5842)
					(thickness 0.1524)
				)
				(justify left mirror)
			)
		)
		(property "Value" ""
			(at 0 0 0)
			(layer "B.Fab")
			(effects
				(font
					(size 1.27 1.27)
				)
				(justify mirror)
			)
		)
		(duplicate_pad_numbers_are_jumpers no)
		(fp_line
			(start 2.2987 7.3533)
			(end 1.7272 7.3533)
			(stroke
				(width 0.1524)
				(type default)
			)
			(layer "B.SilkS")
		)
		(fp_line
			(start 2.2987 -0.2413)
			(end 2.2987 7.3533)
			(stroke
				(width 0.1524)
				(type default)
			)
			(layer "B.SilkS")
		)
		(fp_line
			(start 2.032 1.524)
			(end 1.7272 1.524)
			(stroke
				(width 0.1524)
				(type default)
			)
			(layer "B.SilkS")
		)
		(fp_line
			(start 2.032 -0.2413)
			(end 2.2987 -0.2413)
			(stroke
				(width 0.1524)
				(type default)
			)
			(layer "B.SilkS")
		)
		(fp_line
			(start 2.032 -1.524)
			(end 2.032 1.524)
			(stroke
				(width 0.1524)
				(type default)
			)
			(layer "B.SilkS")
		)
		(fp_line
			(start 1.7272 -1.524)
			(end 2.032 -1.524)
			(stroke
				(width 0.1524)
				(type default)
			)
			(layer "B.SilkS")
		)
		(fp_line
			(start -1.7272 7.3533)
			(end -2.2987 7.3533)
			(stroke
				(width 0.1524)
				(type default)
			)
			(layer "B.SilkS")
		)
		(fp_line
			(start -1.7272 -1.524)
			(end -2.032 -1.524)
			(stroke
				(width 0.1524)
				(type default)
			)
			(layer "B.SilkS")
		)
		(fp_line
			(start -2.032 1.524)
			(end -1.7272 1.524)
			(stroke
				(width 0.1524)
				(type default)
			)
			(layer "B.SilkS")
		)
		(fp_line
			(start -2.032 -1.524)
			(end -2.032 1.524)
			(stroke
				(width 0.1524)
				(type default)
			)
			(layer "B.SilkS")
		)
		(fp_line
			(start -2.2987 7.3533)
			(end -2.2987 -0.2413)
			(stroke
				(width 0.1524)
				(type default)
			)
			(layer "B.SilkS")
		)
		(fp_line
			(start -2.2987 -0.2413)
			(end -2.032 -0.2413)
			(stroke
				(width 0.1524)
				(type default)
			)
			(layer "B.SilkS")
		)
		(fp_rect
			(start 2.2987 -0.2413)
			(end -2.2987 7.3533)
			(stroke
				(width 0)
				(type default)
			)
			(fill no)
			(layer "B.CrtYd")
		)
		(fp_line
			(start 2.2987 7.3533)
			(end 2.2987 -0.2413)
			(stroke
				(width 0.1)
				(type default)
			)
			(layer "B.Fab")
		)
		(fp_line
			(start 2.2987 -0.2413)
			(end -2.2987 -0.2413)
			(stroke
				(width 0.1)
				(type default)
			)
			(layer "B.Fab")
		)
		(fp_line
			(start -2.2987 7.3533)
			(end 2.2987 7.3533)
			(stroke
				(width 0.1)
				(type default)
			)
			(layer "B.Fab")
		)
		(fp_line
			(start -2.2987 -0.2413)
			(end -2.2987 7.3533)
			(stroke
				(width 0.1)
				(type default)
			)
			(layer "B.Fab")
		)
		(pad "1" smd rect
			(at 0 0)
			(size 2.54 3.048)
			(layers "B.Cu" "B.Mask" "B.Paste")
			(net "PVPP_ABC")
		)
		(pad "2" smd rect
			(at 0 7.112)
			(size 2.54 3.048)
			(layers "B.Cu" "B.Mask" "B.Paste")
			(net "GND")
		)
	)
	(footprint ""
		(layer "B.Cu")
		(at 347.5736 -5.5118 -90)
		(property "Reference" "C3U3"
			(at 0 0 90)
			(layer "B.SilkS")
			(hide yes)
			(effects
				(font
					(size 1.27 1.27)
				)
				(justify mirror)
			)
		)
		(property "Value" ""
			(at 0 0 90)
			(layer "B.Fab")
			(effects
				(font
					(size 1.27 1.27)
				)
				(justify mirror)
			)
		)
		(duplicate_pad_numbers_are_jumpers no)
		(fp_rect
			(start 0.7239 1.9939)
			(end -0.7239 -0.2159)
			(stroke
				(width 0)
				(type default)
			)
			(fill no)
			(layer "B.CrtYd")
		)
		(fp_line
			(start -0.7239 1.9939)
			(end -0.7239 -0.2159)
			(stroke
				(width 0.1)
				(type default)
			)
			(layer "B.Fab")
		)
		(fp_line
			(start 0.7239 1.9939)
			(end -0.7239 1.9939)
			(stroke
				(width 0.1)
				(type default)
			)
			(layer "B.Fab")
		)
		(fp_line
			(start -0.7239 -0.2159)
			(end 0.7239 -0.2159)
			(stroke
				(width 0.1)
				(type default)
			)
			(layer "B.Fab")
		)
		(fp_line
			(start 0.7239 -0.2159)
			(end 0.7239 1.9939)
			(stroke
				(width 0.1)
				(type default)
			)
			(layer "B.Fab")
		)
		(pad "1" smd rect
			(at 0 0 90)
			(size 1.27 1.016)
			(layers "B.Cu" "B.Mask" "B.Paste")
			(net "VR_FET_SW_P12V_STBY_PVDDQ_ABC")
		)
		(pad "2" smd rect
			(at 0 1.778 90)
			(size 1.27 1.016)
			(layers "B.Cu" "B.Mask" "B.Paste")
			(net "GND")
		)
		(zone
			(layer "B.Cu")
			(hatch none 0.5)
			(connect_pads
				(clearance 0)
			)
			(min_thickness 0.25)
			(keepout
				(tracks not_allowed)
				(vias allowed)
				(pads allowed)
				(copperpour not_allowed)
				(footprints allowed)
			)
			(placement
				(enabled no)
				(sheetname "")
			)
			(fill
				(thermal_gap 0.5)
				(thermal_bridge_width 0.5)
				(island_removal_mode 0)
			)
			(polygon
				(pts
					(xy 346.3036 -4.8768) (xy 347.0656 -4.8768) (xy 347.0656 -6.1468) (xy 346.3036 -6.1468)
				)
			)
		)
	)
	(footprint ""
		(layer "B.Cu")
		(at 179.804822 -20.014692 180)
		(property "Reference" "R6T9"
			(at 0 0 0)
			(layer "B.SilkS")
			(hide yes)
			(effects
				(font
					(size 1.27 1.27)
				)
				(justify mirror)
			)
		)
		(property "Value" ""
			(at 0 0 0)
			(layer "B.Fab")
			(effects
				(font
					(size 1.27 1.27)
				)
				(justify mirror)
			)
		)
		(duplicate_pad_numbers_are_jumpers no)
		(fp_rect
			(start 0.2794 0.9906)
			(end -0.2794 -0.1016)
			(stroke
				(width 0)
				(type default)
			)
			(fill no)
			(layer "B.CrtYd")
		)
		(fp_line
			(start 0.2794 0.9906)
			(end -0.2794 0.9906)
			(stroke
				(width 0.1)
				(type default)
			)
			(layer "B.Fab")
		)
		(fp_line
			(start 0.2794 -0.1016)
			(end 0.2794 0.9906)
			(stroke
				(width 0.1)
				(type default)
			)
			(layer "B.Fab")
		)
		(fp_line
			(start -0.2794 0.9906)
			(end -0.2794 -0.1016)
			(stroke
				(width 0.1)
				(type default)
			)
			(layer "B.Fab")
		)
		(fp_line
			(start -0.2794 -0.1016)
			(end 0.2794 -0.1016)
			(stroke
				(width 0.1)
				(type default)
			)
			(layer "B.Fab")
		)
		(pad "1" smd rect
			(at 0 0)
			(size 0.508 0.508)
			(layers "B.Cu" "B.Mask" "B.Paste")
			(net "PVCCIO_CPU0")
		)
		(pad "2" smd rect
			(at 0 0.889)
			(size 0.508 0.508)
			(layers "B.Cu" "B.Mask" "B.Paste")
			(net "XDP_CPU_OBSFN_B1_MBP7_N")
		)
		(zone
			(layer "B.Cu")
			(hatch none 0.5)
			(connect_pads
				(clearance 0)
			)
			(min_thickness 0.25)
			(keepout
				(tracks allowed)
				(vias not_allowed)
				(pads allowed)
				(copperpour not_allowed)
				(footprints allowed)
			)
			(placement
				(enabled no)
				(sheetname "")
			)
			(fill
				(thermal_gap 0.5)
				(thermal_bridge_width 0.5)
				(island_removal_mode 0)
			)
			(polygon
				(pts
					(xy 179.550822 -20.649692) (xy 179.550822 -20.268692) (xy 180.058822 -20.268692) (xy 180.058822 -20.649692)
				)
			)
		)
		(zone
			(layer "B.Cu")
			(hatch none 0.5)
			(connect_pads
				(clearance 0)
			)
			(min_thickness 0.25)
			(keepout
				(tracks not_allowed)
				(vias allowed)
				(pads allowed)
				(copperpour not_allowed)
				(footprints allowed)
			)
			(placement
				(enabled no)
				(sheetname "")
			)
			(fill
				(thermal_gap 0.5)
				(thermal_bridge_width 0.5)
				(island_removal_mode 0)
			)
			(polygon
				(pts
					(xy 179.550822 -20.649692) (xy 179.550822 -20.268692) (xy 180.058822 -20.268692) (xy 180.058822 -20.649692)
				)
			)
		)
	)
)
